(kicad_pcb
	(version 20260206)
	(generator "pcbnew")
	(generator_version "10.0")
	(general
		(thickness 1.6)
		(legacy_teardrops no)
	)
	(paper "A4")
	(title_block
		(title "12092022_DA0F0TFB6D0_F0T_FAN_BOARD_MP5048_D_brd_v02_OCP.brd")
		(comment 1 "Grand Teton / footprints 86-91 of 924")
	)
	(layers
		(0 "F.Cu" signal "TOP")
		(4 "In1.Cu" signal "GND")
		(6 "In2.Cu" signal "IN1")
		(8 "In3.Cu" signal "IN2")
		(10 "In4.Cu" signal "GND1")
		(2 "B.Cu" signal "BOTTOM")
		(9 "F.Adhes" user "F.Adhesive")
		(11 "B.Adhes" user "B.Adhesive")
		(13 "F.Paste" user "Package Geometry/Pastemask Top")
		(15 "B.Paste" user "Package Geometry/Pastemask Bottom")
		(5 "F.SilkS" user "Ref Des/Silkscreen Top")
		(7 "B.SilkS" user "Ref Des/Silkscreen Bottom")
		(1 "F.Mask" user "Board Geometry/Soldermask Top")
		(3 "B.Mask" user "Board Geometry/Soldermask Bottom")
		(17 "Dwgs.User" user "User.Drawings")
		(19 "Cmts.User" user "User.Comments")
		(21 "Eco1.User" user "User.Eco1")
		(23 "Eco2.User" user "User.Eco2")
		(25 "Edge.Cuts" user "Board Geometry/Outline")
		(27 "Margin" user)
		(31 "F.CrtYd" user "Package Geometry/Place Bound Top")
		(29 "B.CrtYd" user "Package Geometry/Place Bound Bottom")
		(35 "F.Fab" user "Ref Des/Assembly Top")
		(33 "B.Fab" user "Ref Des/Assembly Bottom")
	)
	(footprint ""
		(layer "F.Cu")
		(at 19.558 -22.479 -90)
		(property "Reference" "R4992"
			(at 0 0 270)
			(layer "F.SilkS")
			(hide yes)
			(effects
				(font
					(size 1.27 1.27)
				)
			)
		)
		(property "Value" ""
			(at 0 0 270)
			(layer "F.Fab")
			(effects
				(font
					(size 1.27 1.27)
				)
			)
		)
		(duplicate_pad_numbers_are_jumpers no)
		(fp_line
			(start -0.7874 0.4064)
			(end -0.7874 -0.4064)
			(stroke
				(width 0.1524)
				(type default)
			)
			(layer "F.SilkS")
		)
		(fp_line
			(start 0.7874 0.4064)
			(end -0.7874 0.4064)
			(stroke
				(width 0.1524)
				(type default)
			)
			(layer "F.SilkS")
		)
		(fp_line
			(start -0.7874 -0.4064)
			(end 0.7874 -0.4064)
			(stroke
				(width 0.1524)
				(type default)
			)
			(layer "F.SilkS")
		)
		(fp_line
			(start 0.7874 -0.4064)
			(end 0.7874 0.4064)
			(stroke
				(width 0.1524)
				(type default)
			)
			(layer "F.SilkS")
		)
		(fp_line
			(start -0.67945 0.3048)
			(end -0.67945 -0.305054)
			(stroke
				(width 0.1)
				(type default)
			)
			(layer "F.Fab")
		)
		(fp_line
			(start -0.12065 0.3048)
			(end -0.67945 0.3048)
			(stroke
				(width 0.1)
				(type default)
			)
			(layer "F.Fab")
		)
		(fp_line
			(start 0.120396 0.3048)
			(end 0.120396 0.2794)
			(stroke
				(width 0.1)
				(type default)
			)
			(layer "F.Fab")
		)
		(fp_line
			(start 0.67945 0.3048)
			(end 0.120396 0.3048)
			(stroke
				(width 0.1)
				(type default)
			)
			(layer "F.Fab")
		)
		(fp_line
			(start -0.12065 0.2794)
			(end -0.12065 0.3048)
			(stroke
				(width 0.1)
				(type default)
			)
			(layer "F.Fab")
		)
		(fp_line
			(start 0.120396 0.2794)
			(end -0.12065 0.2794)
			(stroke
				(width 0.1)
				(type default)
			)
			(layer "F.Fab")
		)
		(fp_line
			(start -0.12065 -0.2794)
			(end 0.12065 -0.2794)
			(stroke
				(width 0.1)
				(type default)
			)
			(layer "F.Fab")
		)
		(fp_line
			(start 0.12065 -0.2794)
			(end 0.12065 -0.3048)
			(stroke
				(width 0.1)
				(type default)
			)
			(layer "F.Fab")
		)
		(fp_line
			(start 0.12065 -0.3048)
			(end 0.67945 -0.3048)
			(stroke
				(width 0.1)
				(type default)
			)
			(layer "F.Fab")
		)
		(fp_line
			(start 0.67945 -0.3048)
			(end 0.67945 0.3048)
			(stroke
				(width 0.1)
				(type default)
			)
			(layer "F.Fab")
		)
		(fp_line
			(start -0.67945 -0.305054)
			(end -0.12065 -0.305054)
			(stroke
				(width 0.1)
				(type default)
			)
			(layer "F.Fab")
		)
		(fp_line
			(start -0.12065 -0.305054)
			(end -0.12065 -0.2794)
			(stroke
				(width 0.1)
				(type default)
			)
			(layer "F.Fab")
		)
		(pad "1" smd circle
			(at -0.40005 0 270)
			(size 0 0)
			(layers "F.Cu" "F.Mask" "F.Paste")
			(net "P3V3_AUX")
		)
		(pad "2" smd circle
			(at 0.40005 0 270)
			(size 0 0)
			(layers "F.Cu" "F.Mask" "F.Paste")
			(net "FAN_4_FAIL_R_LED")
		)
	)
	(footprint ""
		(layer "F.Cu")
		(at 40.767 -74.168)
		(property "Reference" "PR39"
			(at 0 0 0)
			(layer "F.SilkS")
			(hide yes)
			(effects
				(font
					(size 1.27 1.27)
				)
			)
		)
		(property "Value" ""
			(at 0 0 0)
			(layer "F.Fab")
			(effects
				(font
					(size 1.27 1.27)
				)
			)
		)
		(duplicate_pad_numbers_are_jumpers no)
		(fp_line
			(start -0.7874 -0.4064)
			(end 0.7874 -0.4064)
			(stroke
				(width 0.1524)
				(type default)
			)
			(layer "F.SilkS")
		)
		(fp_line
			(start -0.7874 0.4064)
			(end -0.7874 -0.4064)
			(stroke
				(width 0.1524)
				(type default)
			)
			(layer "F.SilkS")
		)
		(fp_line
			(start 0.7874 -0.4064)
			(end 0.7874 0.4064)
			(stroke
				(width 0.1524)
				(type default)
			)
			(layer "F.SilkS")
		)
		(fp_line
			(start 0.7874 0.4064)
			(end -0.7874 0.4064)
			(stroke
				(width 0.1524)
				(type default)
			)
			(layer "F.SilkS")
		)
		(fp_line
			(start -0.67945 -0.305054)
			(end -0.12065 -0.305054)
			(stroke
				(width 0.1)
				(type default)
			)
			(layer "F.Fab")
		)
		(fp_line
			(start -0.67945 0.3048)
			(end -0.67945 -0.305054)
			(stroke
				(width 0.1)
				(type default)
			)
			(layer "F.Fab")
		)
		(fp_line
			(start -0.12065 -0.305054)
			(end -0.12065 -0.2794)
			(stroke
				(width 0.1)
				(type default)
			)
			(layer "F.Fab")
		)
		(fp_line
			(start -0.12065 -0.2794)
			(end 0.12065 -0.2794)
			(stroke
				(width 0.1)
				(type default)
			)
			(layer "F.Fab")
		)
		(fp_line
			(start -0.12065 0.2794)
			(end -0.12065 0.3048)
			(stroke
				(width 0.1)
				(type default)
			)
			(layer "F.Fab")
		)
		(fp_line
			(start -0.12065 0.3048)
			(end -0.67945 0.3048)
			(stroke
				(width 0.1)
				(type default)
			)
			(layer "F.Fab")
		)
		(fp_line
			(start 0.120396 0.2794)
			(end -0.12065 0.2794)
			(stroke
				(width 0.1)
				(type default)
			)
			(layer "F.Fab")
		)
		(fp_line
			(start 0.120396 0.3048)
			(end 0.120396 0.2794)
			(stroke
				(width 0.1)
				(type default)
			)
			(layer "F.Fab")
		)
		(fp_line
			(start 0.12065 -0.3048)
			(end 0.67945 -0.3048)
			(stroke
				(width 0.1)
				(type default)
			)
			(layer "F.Fab")
		)
		(fp_line
			(start 0.12065 -0.2794)
			(end 0.12065 -0.3048)
			(stroke
				(width 0.1)
				(type default)
			)
			(layer "F.Fab")
		)
		(fp_line
			(start 0.67945 -0.3048)
			(end 0.67945 0.3048)
			(stroke
				(width 0.1)
				(type default)
			)
			(layer "F.Fab")
		)
		(fp_line
			(start 0.67945 0.3048)
			(end 0.120396 0.3048)
			(stroke
				(width 0.1)
				(type default)
			)
			(layer "F.Fab")
		)
		(pad "1" smd circle
			(at -0.40005 0)
			(size 0 0)
			(layers "F.Cu" "F.Mask" "F.Paste")
			(net "FAN_2_MODE")
		)
		(pad "2" smd circle
			(at 0.40005 0)
			(size 0 0)
			(layers "F.Cu" "F.Mask" "F.Paste")
			(net "GND")
		)
	)
	(footprint ""
		(layer "F.Cu")
		(at 45.593 -31.623 180)
		(property "Reference" "R5696"
			(at 0 0 180)
			(layer "F.SilkS")
			(hide yes)
			(effects
				(font
					(size 1.27 1.27)
				)
			)
		)
		(property "Value" ""
			(at 0 0 180)
			(layer "F.Fab")
			(effects
				(font
					(size 1.27 1.27)
				)
			)
		)
		(duplicate_pad_numbers_are_jumpers no)
		(fp_line
			(start 0.7874 0.4064)
			(end -0.7874 0.4064)
			(stroke
				(width 0.1524)
				(type default)
			)
			(layer "F.SilkS")
		)
		(fp_line
			(start 0.7874 -0.4064)
			(end 0.7874 0.4064)
			(stroke
				(width 0.1524)
				(type default)
			)
			(layer "F.SilkS")
		)
		(fp_line
			(start -0.7874 0.4064)
			(end -0.7874 -0.4064)
			(stroke
				(width 0.1524)
				(type default)
			)
			(layer "F.SilkS")
		)
		(fp_line
			(start -0.7874 -0.4064)
			(end 0.7874 -0.4064)
			(stroke
				(width 0.1524)
				(type default)
			)
			(layer "F.SilkS")
		)
		(fp_line
			(start 0.67945 0.3048)
			(end 0.120396 0.3048)
			(stroke
				(width 0.1)
				(type default)
			)
			(layer "F.Fab")
		)
		(fp_line
			(start 0.67945 -0.3048)
			(end 0.67945 0.3048)
			(stroke
				(width 0.1)
				(type default)
			)
			(layer "F.Fab")
		)
		(fp_line
			(start 0.12065 -0.2794)
			(end 0.12065 -0.3048)
			(stroke
				(width 0.1)
				(type default)
			)
			(layer "F.Fab")
		)
		(fp_line
			(start 0.12065 -0.3048)
			(end 0.67945 -0.3048)
			(stroke
				(width 0.1)
				(type default)
			)
			(layer "F.Fab")
		)
		(fp_line
			(start 0.120396 0.3048)
			(end 0.120396 0.2794)
			(stroke
				(width 0.1)
				(type default)
			)
			(layer "F.Fab")
		)
		(fp_line
			(start 0.120396 0.2794)
			(end -0.12065 0.2794)
			(stroke
				(width 0.1)
				(type default)
			)
			(layer "F.Fab")
		)
		(fp_line
			(start -0.12065 0.3048)
			(end -0.67945 0.3048)
			(stroke
				(width 0.1)
				(type default)
			)
			(layer "F.Fab")
		)
		(fp_line
			(start -0.12065 0.2794)
			(end -0.12065 0.3048)
			(stroke
				(width 0.1)
				(type default)
			)
			(layer "F.Fab")
		)
		(fp_line
			(start -0.12065 -0.2794)
			(end 0.12065 -0.2794)
			(stroke
				(width 0.1)
				(type default)
			)
			(layer "F.Fab")
		)
		(fp_line
			(start -0.12065 -0.305054)
			(end -0.12065 -0.2794)
			(stroke
				(width 0.1)
				(type default)
			)
			(layer "F.Fab")
		)
		(fp_line
			(start -0.67945 0.3048)
			(end -0.67945 -0.305054)
			(stroke
				(width 0.1)
				(type default)
			)
			(layer "F.Fab")
		)
		(fp_line
			(start -0.67945 -0.305054)
			(end -0.12065 -0.305054)
			(stroke
				(width 0.1)
				(type default)
			)
			(layer "F.Fab")
		)
		(pad "1" smd rect
			(at -0.40005 0)
			(size 0.4572 0.508)
			(layers "F.Cu" "F.Mask" "F.Paste")
			(net "P12V_LED_R_FAN3")
		)
		(pad "2" smd rect
			(at 0.40005 0)
			(size 0.4572 0.508)
			(layers "F.Cu" "F.Mask" "F.Paste")
			(net "P12V_LED_R1_FAN3")
		)
	)
	(footprint ""
		(layer "F.Cu")
		(at 18.034 -136.017 -90)
		(property "Reference" "R4950"
			(at 0 0 270)
			(layer "F.SilkS")
			(hide yes)
			(effects
				(font
					(size 1.27 1.27)
				)
			)
		)
		(property "Value" ""
			(at 0 0 270)
			(layer "F.Fab")
			(effects
				(font
					(size 1.27 1.27)
				)
			)
		)
		(duplicate_pad_numbers_are_jumpers no)
		(fp_line
			(start -0.7874 0.4064)
			(end -0.7874 -0.4064)
			(stroke
				(width 0.1524)
				(type default)
			)
			(layer "F.SilkS")
		)
		(fp_line
			(start 0.7874 0.4064)
			(end -0.7874 0.4064)
			(stroke
				(width 0.1524)
				(type default)
			)
			(layer "F.SilkS")
		)
		(fp_line
			(start -0.7874 -0.4064)
			(end 0.7874 -0.4064)
			(stroke
				(width 0.1524)
				(type default)
			)
			(layer "F.SilkS")
		)
		(fp_line
			(start 0.7874 -0.4064)
			(end 0.7874 0.4064)
			(stroke
				(width 0.1524)
				(type default)
			)
			(layer "F.SilkS")
		)
		(fp_line
			(start -0.67945 0.3048)
			(end -0.67945 -0.305054)
			(stroke
				(width 0.1)
				(type default)
			)
			(layer "F.Fab")
		)
		(fp_line
			(start -0.12065 0.3048)
			(end -0.67945 0.3048)
			(stroke
				(width 0.1)
				(type default)
			)
			(layer "F.Fab")
		)
		(fp_line
			(start 0.120396 0.3048)
			(end 0.120396 0.2794)
			(stroke
				(width 0.1)
				(type default)
			)
			(layer "F.Fab")
		)
		(fp_line
			(start 0.67945 0.3048)
			(end 0.120396 0.3048)
			(stroke
				(width 0.1)
				(type default)
			)
			(layer "F.Fab")
		)
		(fp_line
			(start -0.12065 0.2794)
			(end -0.12065 0.3048)
			(stroke
				(width 0.1)
				(type default)
			)
			(layer "F.Fab")
		)
		(fp_line
			(start 0.120396 0.2794)
			(end -0.12065 0.2794)
			(stroke
				(width 0.1)
				(type default)
			)
			(layer "F.Fab")
		)
		(fp_line
			(start -0.12065 -0.2794)
			(end 0.12065 -0.2794)
			(stroke
				(width 0.1)
				(type default)
			)
			(layer "F.Fab")
		)
		(fp_line
			(start 0.12065 -0.2794)
			(end 0.12065 -0.3048)
			(stroke
				(width 0.1)
				(type default)
			)
			(layer "F.Fab")
		)
		(fp_line
			(start 0.12065 -0.3048)
			(end 0.67945 -0.3048)
			(stroke
				(width 0.1)
				(type default)
			)
			(layer "F.Fab")
		)
		(fp_line
			(start 0.67945 -0.3048)
			(end 0.67945 0.3048)
			(stroke
				(width 0.1)
				(type default)
			)
			(layer "F.Fab")
		)
		(fp_line
			(start -0.67945 -0.305054)
			(end -0.12065 -0.305054)
			(stroke
				(width 0.1)
				(type default)
			)
			(layer "F.Fab")
		)
		(fp_line
			(start -0.12065 -0.305054)
			(end -0.12065 -0.2794)
			(stroke
				(width 0.1)
				(type default)
			)
			(layer "F.Fab")
		)
		(pad "1" smd circle
			(at -0.40005 0 270)
			(size 0 0)
			(layers "F.Cu" "F.Mask" "F.Paste")
			(net "GND")
		)
		(pad "2" smd circle
			(at 0.40005 0 270)
			(size 0 0)
			(layers "F.Cu" "F.Mask" "F.Paste")
			(net "MAX31790_U330_WD_START")
		)
	)
	(footprint ""
		(layer "F.Cu")
		(at 43.561 -165.481 180)
		(property "Reference" "R5112"
			(at 0 0 180)
			(layer "F.SilkS")
			(hide yes)
			(effects
				(font
					(size 1.27 1.27)
				)
			)
		)
		(property "Value" ""
			(at 0 0 180)
			(layer "F.Fab")
			(effects
				(font
					(size 1.27 1.27)
				)
			)
		)
		(duplicate_pad_numbers_are_jumpers no)
		(fp_line
			(start 0.7874 0.4064)
			(end -0.7874 0.4064)
			(stroke
				(width 0.1524)
				(type default)
			)
			(layer "F.SilkS")
		)
		(fp_line
			(start 0.7874 -0.4064)
			(end 0.7874 0.4064)
			(stroke
				(width 0.1524)
				(type default)
			)
			(layer "F.SilkS")
		)
		(fp_line
			(start -0.7874 0.4064)
			(end -0.7874 -0.4064)
			(stroke
				(width 0.1524)
				(type default)
			)
			(layer "F.SilkS")
		)
		(fp_line
			(start -0.7874 -0.4064)
			(end 0.7874 -0.4064)
			(stroke
				(width 0.1524)
				(type default)
			)
			(layer "F.SilkS")
		)
		(fp_line
			(start 0.67945 0.3048)
			(end 0.120396 0.3048)
			(stroke
				(width 0.1)
				(type default)
			)
			(layer "F.Fab")
		)
		(fp_line
			(start 0.67945 -0.3048)
			(end 0.67945 0.3048)
			(stroke
				(width 0.1)
				(type default)
			)
			(layer "F.Fab")
		)
		(fp_line
			(start 0.12065 -0.2794)
			(end 0.12065 -0.3048)
			(stroke
				(width 0.1)
				(type default)
			)
			(layer "F.Fab")
		)
		(fp_line
			(start 0.12065 -0.3048)
			(end 0.67945 -0.3048)
			(stroke
				(width 0.1)
				(type default)
			)
			(layer "F.Fab")
		)
		(fp_line
			(start 0.120396 0.3048)
			(end 0.120396 0.2794)
			(stroke
				(width 0.1)
				(type default)
			)
			(layer "F.Fab")
		)
		(fp_line
			(start 0.120396 0.2794)
			(end -0.12065 0.2794)
			(stroke
				(width 0.1)
				(type default)
			)
			(layer "F.Fab")
		)
		(fp_line
			(start -0.12065 0.3048)
			(end -0.67945 0.3048)
			(stroke
				(width 0.1)
				(type default)
			)
			(layer "F.Fab")
		)
		(fp_line
			(start -0.12065 0.2794)
			(end -0.12065 0.3048)
			(stroke
				(width 0.1)
				(type default)
			)
			(layer "F.Fab")
		)
		(fp_line
			(start -0.12065 -0.2794)
			(end 0.12065 -0.2794)
			(stroke
				(width 0.1)
				(type default)
			)
			(layer "F.Fab")
		)
		(fp_line
			(start -0.12065 -0.305054)
			(end -0.12065 -0.2794)
			(stroke
				(width 0.1)
				(type default)
			)
			(layer "F.Fab")
		)
		(fp_line
			(start -0.67945 0.3048)
			(end -0.67945 -0.305054)
			(stroke
				(width 0.1)
				(type default)
			)
			(layer "F.Fab")
		)
		(fp_line
			(start -0.67945 -0.305054)
			(end -0.12065 -0.305054)
			(stroke
				(width 0.1)
				(type default)
			)
			(layer "F.Fab")
		)
		(pad "1" smd circle
			(at -0.40005 0 180)
			(size 0 0)
			(layers "F.Cu" "F.Mask" "F.Paste")
			(net "P3V3_AUX")
		)
		(pad "2" smd circle
			(at 0.40005 0 180)
			(size 0 0)
			(layers "F.Cu" "F.Mask" "F.Paste")
			(net "PCA9552_MB1_A0")
		)
	)
	(footprint ""
		(layer "F.Cu")
		(at 35.306 -64.897 -90)
		(property "Reference" "PR22"
			(at 0 0 270)
			(layer "F.SilkS")
			(hide yes)
			(effects
				(font
					(size 1.27 1.27)
				)
			)
		)
		(property "Value" ""
			(at 0 0 270)
			(layer "F.Fab")
			(effects
				(font
					(size 1.27 1.27)
				)
			)
		)
		(duplicate_pad_numbers_are_jumpers no)
		(fp_line
			(start -0.7874 0.4064)
			(end -0.7874 -0.4064)
			(stroke
				(width 0.1524)
				(type default)
			)
			(layer "F.SilkS")
		)
		(fp_line
			(start 0.7874 0.4064)
			(end -0.7874 0.4064)
			(stroke
				(width 0.1524)
				(type default)
			)
			(layer "F.SilkS")
		)
		(fp_line
			(start -0.7874 -0.4064)
			(end 0.7874 -0.4064)
			(stroke
				(width 0.1524)
				(type default)
			)
			(layer "F.SilkS")
		)
		(fp_line
			(start 0.7874 -0.4064)
			(end 0.7874 0.4064)
			(stroke
				(width 0.1524)
				(type default)
			)
			(layer "F.SilkS")
		)
		(fp_line
			(start -0.67945 0.3048)
			(end -0.67945 -0.305054)
			(stroke
				(width 0.1)
				(type default)
			)
			(layer "F.Fab")
		)
		(fp_line
			(start -0.12065 0.3048)
			(end -0.67945 0.3048)
			(stroke
				(width 0.1)
				(type default)
			)
			(layer "F.Fab")
		)
		(fp_line
			(start 0.120396 0.3048)
			(end 0.120396 0.2794)
			(stroke
				(width 0.1)
				(type default)
			)
			(layer "F.Fab")
		)
		(fp_line
			(start 0.67945 0.3048)
			(end 0.120396 0.3048)
			(stroke
				(width 0.1)
				(type default)
			)
			(layer "F.Fab")
		)
		(fp_line
			(start -0.12065 0.2794)
			(end -0.12065 0.3048)
			(stroke
				(width 0.1)
				(type default)
			)
			(layer "F.Fab")
		)
		(fp_line
			(start 0.120396 0.2794)
			(end -0.12065 0.2794)
			(stroke
				(width 0.1)
				(type default)
			)
			(layer "F.Fab")
		)
		(fp_line
			(start -0.12065 -0.2794)
			(end 0.12065 -0.2794)
			(stroke
				(width 0.1)
				(type default)
			)
			(layer "F.Fab")
		)
		(fp_line
			(start 0.12065 -0.2794)
			(end 0.12065 -0.3048)
			(stroke
				(width 0.1)
				(type default)
			)
			(layer "F.Fab")
		)
		(fp_line
			(start 0.12065 -0.3048)
			(end 0.67945 -0.3048)
			(stroke
				(width 0.1)
				(type default)
			)
			(layer "F.Fab")
		)
		(fp_line
			(start 0.67945 -0.3048)
			(end 0.67945 0.3048)
			(stroke
				(width 0.1)
				(type default)
			)
			(layer "F.Fab")
		)
		(fp_line
			(start -0.67945 -0.305054)
			(end -0.12065 -0.305054)
			(stroke
				(width 0.1)
				(type default)
			)
			(layer "F.Fab")
		)
		(fp_line
			(start -0.12065 -0.305054)
			(end -0.12065 -0.2794)
			(stroke
				(width 0.1)
				(type default)
			)
			(layer "F.Fab")
		)
		(pad "1" smd rect
			(at -0.40005 0 90)
			(size 0.4572 0.508)
			(layers "F.Cu" "F.Mask" "F.Paste")
			(net "FAN_3_FAULT_R")
		)
		(pad "2" smd rect
			(at 0.40005 0 90)
			(size 0.4572 0.508)
			(layers "F.Cu" "F.Mask" "F.Paste")
			(net "FAN_3_FAULT")
		)
	)
)
